# S9S_MB_2U (Grand Teton) — schematic netlist excerpt (pin names and nets, part order shuffled) for the footprints in the layout excerpt that follows; sources: Cadence DE-HDL packaged netlist, KiCad conversion of 03242023_DA0F0TMBIJ0_F0T_Motherboard_J_brd_V01_OCP.brd

R2787  Q_RES  0 5% CHIP  pkg 0402LF  page 152 : A = USB2_HUB_SWB_DN ; B = USB2_HUB_BUF_SWB_R_DN

(kicad_pcb
	(version 20260206)
	(generator "pcbnew")
	(generator_version "10.0")
	(general
		(thickness 1.6)
		(legacy_teardrops no)
	)
	(paper "A4")
	(title_block
		(title "03242023_DA0F0TMBIJ0_F0T_Motherboard_J_brd_V01_OCP.brd")
		(comment 1 "Grand Teton / footprints 2235-2235 of 6105")
	)
	(layers
		(0 "F.Cu" signal "TOP")
		(4 "In1.Cu" signal "GND")
		(6 "In2.Cu" signal "IN1")
		(8 "In3.Cu" signal "GND1")
		(10 "In4.Cu" signal "IN2")
		(12 "In5.Cu" signal "GND2")
		(14 "In6.Cu" signal "IN3")
		(16 "In7.Cu" signal "GND3")
		(18 "In8.Cu" signal "VCC")
		(20 "In9.Cu" signal "VCC1")
		(22 "In10.Cu" signal "GND4")
		(24 "In11.Cu" signal "IN4")
		(26 "In12.Cu" signal "GND5")
		(28 "In13.Cu" signal "IN5")
		(30 "In14.Cu" signal "GND6")
		(32 "In15.Cu" signal "IN6")
		(34 "In16.Cu" signal "GND7")
		(2 "B.Cu" signal "BOTTOM")
		(9 "F.Adhes" user "F.Adhesive")
		(11 "B.Adhes" user "B.Adhesive")
		(13 "F.Paste" user "Package Geometry/Pastemask Top")
		(15 "B.Paste" user "Package Geometry/Pastemask Bottom")
		(5 "F.SilkS" user "Ref Des/Silkscreen Top")
		(7 "B.SilkS" user "Ref Des/Silkscreen Bottom")
		(1 "F.Mask" user "Board Geometry/Soldermask Top")
		(3 "B.Mask" user "Board Geometry/Soldermask Bottom")
		(17 "Dwgs.User" user "User.Drawings")
		(19 "Cmts.User" user "User.Comments")
		(21 "Eco1.User" user "User.Eco1")
		(23 "Eco2.User" user "User.Eco2")
		(25 "Edge.Cuts" user "Board Geometry/Outline")
		(27 "Margin" user)
		(31 "F.CrtYd" user "Package Geometry/Place Bound Top")
		(29 "B.CrtYd" user "Package Geometry/Place Bound Bottom")
		(35 "F.Fab" user "Ref Des/Assembly Top")
		(33 "B.Fab" user "Ref Des/Assembly Bottom")
	)
	(footprint ""
		(layer "F.Cu")
		(at 12.786106 -105.50398 90)
		(property "Reference" "R2787"
			(at 0 0 90)
			(layer "F.SilkS")
			(hide yes)
			(effects
				(font
					(size 1.27 1.27)
				)
			)
		)
		(property "Value" ""
			(at 0 0 90)
			(layer "F.Fab")
			(effects
				(font
					(size 1.27 1.27)
				)
			)
		)
		(duplicate_pad_numbers_are_jumpers no)
		(fp_line
			(start 0.7874 -0.4064)
			(end 0.7874 0.4064)
			(stroke
				(width 0.1524)
				(type default)
			)
			(layer "F.SilkS")
		)
		(fp_line
			(start -0.7874 -0.4064)
			(end 0.06604 -0.4064)
			(stroke
				(width 0.1524)
				(type default)
			)
			(layer "F.SilkS")
		)
		(fp_line
			(start 0.7874 0.4064)
			(end -0.7874 0.4064)
			(stroke
				(width 0.1524)
				(type default)
			)
			(layer "F.SilkS")
		)
		(fp_line
			(start -0.12065 -0.305054)
			(end -0.12065 -0.2794)
			(stroke
				(width 0.1)
				(type default)
			)
			(layer "F.Fab")
		)
		(fp_line
			(start -0.67945 -0.305054)
			(end -0.12065 -0.305054)
			(stroke
				(width 0.1)
				(type default)
			)
			(layer "F.Fab")
		)
		(fp_line
			(start 0.67945 -0.3048)
			(end 0.67945 0.3048)
			(stroke
				(width 0.1)
				(type default)
			)
			(layer "F.Fab")
		)
		(fp_line
			(start 0.12065 -0.3048)
			(end 0.67945 -0.3048)
			(stroke
				(width 0.1)
				(type default)
			)
			(layer "F.Fab")
		)
		(fp_line
			(start 0.12065 -0.2794)
			(end 0.12065 -0.3048)
			(stroke
				(width 0.1)
				(type default)
			)
			(layer "F.Fab")
		)
		(fp_line
			(start -0.12065 -0.2794)
			(end 0.12065 -0.2794)
			(stroke
				(width 0.1)
				(type default)
			)
			(layer "F.Fab")
		)
		(fp_line
			(start 0.120396 0.2794)
			(end -0.12065 0.2794)
			(stroke
				(width 0.1)
				(type default)
			)
			(layer "F.Fab")
		)
		(fp_line
			(start -0.12065 0.2794)
			(end -0.12065 0.3048)
			(stroke
				(width 0.1)
				(type default)
			)
			(layer "F.Fab")
		)
		(fp_line
			(start 0.67945 0.3048)
			(end 0.120396 0.3048)
			(stroke
				(width 0.1)
				(type default)
			)
			(layer "F.Fab")
		)
		(fp_line
			(start 0.120396 0.3048)
			(end 0.120396 0.2794)
			(stroke
				(width 0.1)
				(type default)
			)
			(layer "F.Fab")
		)
		(fp_line
			(start -0.12065 0.3048)
			(end -0.67945 0.3048)
			(stroke
				(width 0.1)
				(type default)
			)
			(layer "F.Fab")
		)
		(fp_line
			(start -0.67945 0.3048)
			(end -0.67945 -0.305054)
			(stroke
				(width 0.1)
				(type default)
			)
			(layer "F.Fab")
		)
		(pad "1" smd rect
			(at -0.40005 0 270)
			(size 0.4572 0.508)
			(layers "F.Cu" "F.Mask" "F.Paste")
			(net "USB2_HUB_SWB_DN")
		)
		(pad "2" smd rect
			(at 0.40005 0 270)
			(size 0.4572 0.508)
			(layers "F.Cu" "F.Mask" "F.Paste")
			(net "USB2_HUB_BUF_SWB_R_DN")
		)
	)
)
